(kicad_pcb
	(version 20260206)
	(generator "pcbnew")
	(generator_version "10.0")
	(general
		(thickness 1.6)
		(legacy_teardrops no)
	)
	(paper "A4")
	(title_block
		(title "Bryce Canyon_F.DPB_16315-1-OCP.brd")
		(comment 1 "Bryce Canyon / footprints 1253-1259 of 2223")
	)
	(layers
		(0 "F.Cu" signal "TOP")
		(4 "In1.Cu" signal "L2GND")
		(6 "In2.Cu" signal "L3")
		(8 "In3.Cu" signal "L4GND")
		(10 "In4.Cu" signal "L5")
		(12 "In5.Cu" signal "L6VCC")
		(14 "In6.Cu" signal "L7VCC")
		(16 "In7.Cu" signal "L8")
		(18 "In8.Cu" signal "L9GND")
		(20 "In9.Cu" signal "L10")
		(22 "In10.Cu" signal "L11GND")
		(2 "B.Cu" signal "BOTTOM")
		(9 "F.Adhes" user "F.Adhesive")
		(11 "B.Adhes" user "B.Adhesive")
		(13 "F.Paste" user "Package Geometry/Pastemask Top")
		(15 "B.Paste" user "Package Geometry/Pastemask Bottom")
		(5 "F.SilkS" user "Ref Des/Silkscreen Top")
		(7 "B.SilkS" user "Ref Des/Silkscreen Bottom")
		(1 "F.Mask" user "Board Geometry/Soldermask Top")
		(3 "B.Mask" user "Board Geometry/Soldermask Bottom")
		(17 "Dwgs.User" user "User.Drawings")
		(19 "Cmts.User" user "User.Comments")
		(21 "Eco1.User" user "User.Eco1")
		(23 "Eco2.User" user "User.Eco2")
		(25 "Edge.Cuts" user "Board Geometry/Outline")
		(27 "Margin" user)
		(31 "F.CrtYd" user "Package Geometry/Place Bound Top")
		(29 "B.CrtYd" user "Package Geometry/Place Bound Bottom")
		(35 "F.Fab" user "Ref Des/Assembly Top")
		(33 "B.Fab" user "Ref Des/Assembly Bottom")
	)
	(footprint ""
		(layer "F.Cu")
		(at 258.8514 13.470128)
		(property "Reference" "Q2"
			(at 0 0 0)
			(layer "F.SilkS")
			(hide yes)
			(effects
				(font
					(size 1.27 1.27)
				)
			)
		)
		(property "Value" "2N7002KDW-GP"
			(at -2.3622 -8.2042 0)
			(unlocked yes)
			(layer "F.Fab")
			(hide yes)
			(effects
				(font
					(size 1.016 1.016)
					(thickness 0.1524)
				)
			)
		)
		(property "Device Type" "SOT-363H44"
			(at -2.3622 -10.1092 0)
			(unlocked yes)
			(layer "F.Fab")
			(hide yes)
			(effects
				(font
					(size 1.016 1.016)
					(thickness 0.1524)
				)
			)
		)
		(duplicate_pad_numbers_are_jumpers no)
		(fp_line
			(start -1.4478 -1.7018)
			(end -1.4478 1.7018)
			(stroke
				(width 0.1524)
				(type default)
			)
			(layer "F.SilkS")
		)
		(fp_line
			(start -1.4478 1.7018)
			(end 1.4478 1.7018)
			(stroke
				(width 0.1524)
				(type default)
			)
			(layer "F.SilkS")
		)
		(fp_line
			(start -1.27 1.524)
			(end -1.27 0.6604)
			(stroke
				(width 0.4826)
				(type default)
			)
			(layer "F.SilkS")
		)
		(fp_line
			(start 1.4478 -1.7018)
			(end -1.4478 -1.7018)
			(stroke
				(width 0.1524)
				(type default)
			)
			(layer "F.SilkS")
		)
		(fp_line
			(start 1.4478 1.7018)
			(end 1.4478 -1.7018)
			(stroke
				(width 0.1524)
				(type default)
			)
			(layer "F.SilkS")
		)
		(fp_poly
			(pts
				(xy -1.524 -1.778) (xy 1.524 -1.778) (xy 1.524 1.778) (xy -1.524 1.778)
			)
			(stroke
				(width 0)
				(type default)
			)
			(fill no)
			(layer "F.CrtYd")
		)
		(fp_poly
			(pts
				(xy -1.524 -1.778) (xy 1.524 -1.778) (xy 1.524 1.778) (xy -1.524 1.778)
			)
			(stroke
				(width 0)
				(type default)
			)
			(fill no)
			(layer "F.Fab")
		)
		(pad "1" smd rect
			(at -0.65024 0.9398)
			(size 0.4064 1.016)
			(layers "F.Cu" "F.Mask" "F.Paste")
			(net "GND")
		)
		(pad "2" smd rect
			(at 0 0.9398)
			(size 0.4064 1.016)
			(layers "F.Cu" "F.Mask" "F.Paste")
			(net "SCC_A_FAULT_LED")
		)
		(pad "3" smd rect
			(at 0.65024 0.9398)
			(size 0.4064 1.016)
			(layers "F.Cu" "F.Mask" "F.Paste")
			(net "ENCL_FAULT_LED_A")
		)
		(pad "4" smd rect
			(at 0.65024 -0.9398)
			(size 0.4064 1.016)
			(layers "F.Cu" "F.Mask" "F.Paste")
			(net "GND")
		)
		(pad "5" smd rect
			(at 0 -0.9398)
			(size 0.4064 1.016)
			(layers "F.Cu" "F.Mask" "F.Paste")
			(net "IOM_A_FAULT_LED")
		)
		(pad "6" smd rect
			(at -0.65024 -0.9398)
			(size 0.4064 1.016)
			(layers "F.Cu" "F.Mask" "F.Paste")
			(net "ENCL_FAULT_LED_A")
		)
	)
	(footprint ""
		(layer "F.Cu")
		(at 148.406866 -144.737074 180)
		(property "Reference" "C549"
			(at 0 0 180)
			(layer "F.SilkS")
			(hide yes)
			(effects
				(font
					(size 1.27 1.27)
				)
			)
		)
		(property "Value" "SC1U16V3KX-5GP"
			(at 0 -2.8194 180)
			(unlocked yes)
			(layer "F.Fab")
			(hide yes)
			(effects
				(font
					(size 1.016 1.016)
					(thickness 0.1524)
				)
			)
		)
		(property "Device Type" "C603H36"
			(at 0 -4.3434 180)
			(unlocked yes)
			(layer "F.Fab")
			(hide yes)
			(effects
				(font
					(size 1.016 1.016)
					(thickness 0.1524)
				)
			)
		)
		(duplicate_pad_numbers_are_jumpers no)
		(fp_line
			(start 0.508 0)
			(end -0.508 0)
			(stroke
				(width 0.2032)
				(type default)
			)
			(layer "F.SilkS")
		)
		(fp_rect
			(start -0.5842 1.3335)
			(end 0.5842 -1.3335)
			(stroke
				(width 0)
				(type default)
			)
			(fill no)
			(layer "F.CrtYd")
		)
		(fp_rect
			(start -0.5842 1.3335)
			(end 0.5842 -1.3335)
			(stroke
				(width 0)
				(type default)
			)
			(fill no)
			(layer "F.Fab")
		)
		(pad "1" smd custom
			(at 0 -0.762 180)
			(size 0.2159 0.2159)
			(layers "F.Cu" "F.Mask" "F.Paste")
			(net "MB0_VCAP_R")
			(options
				(clearance outline)
				(anchor circle)
			)
			(primitives
				(gr_poly
					(pts
						(arc
							(start -0.3302 -0.4318)
							(mid -0.402042 -0.402042)
							(end -0.4318 -0.3302)
						)
						(arc
							(start -0.4318 0.3302)
							(mid -0.402042 0.402042)
							(end -0.3302 0.4318)
						)
						(arc
							(start 0.3302 0.4318)
							(mid 0.402042 0.402042)
							(end 0.4318 0.3302)
						)
						(arc
							(start 0.4318 -0.3302)
							(mid 0.402042 -0.402042)
							(end 0.3302 -0.4318)
						)
					)
					(width 0)
					(fill yes)
				)
			)
		)
		(pad "2" smd custom
			(at 0 0.762 180)
			(size 0.2159 0.2159)
			(layers "F.Cu" "F.Mask" "F.Paste")
			(net "AGND_CURRENT_MONOA")
			(options
				(clearance outline)
				(anchor circle)
			)
			(primitives
				(gr_poly
					(pts
						(arc
							(start -0.3302 -0.4318)
							(mid -0.402042 -0.402042)
							(end -0.4318 -0.3302)
						)
						(arc
							(start -0.4318 0.3302)
							(mid -0.402042 0.402042)
							(end -0.3302 0.4318)
						)
						(arc
							(start 0.3302 0.4318)
							(mid 0.402042 0.402042)
							(end 0.4318 0.3302)
						)
						(arc
							(start 0.4318 -0.3302)
							(mid 0.402042 -0.402042)
							(end 0.3302 -0.4318)
						)
					)
					(width 0)
					(fill yes)
				)
			)
		)
	)
	(footprint ""
		(layer "F.Cu")
		(at 52.234846 -170.285918 180)
		(property "Reference" "Q77"
			(at 0 0 180)
			(layer "F.SilkS")
			(hide yes)
			(effects
				(font
					(size 1.27 1.27)
				)
			)
		)
		(property "Value" "AO4406AL-GP"
			(at -3.707384 -1.5367 180)
			(unlocked yes)
			(layer "F.Fab")
			(hide yes)
			(effects
				(font
					(size 1.016 1.016)
					(thickness 0.1524)
				)
			)
		)
		(property "Device Type" "SOIC8H69"
			(at -3.707384 -3.0607 180)
			(unlocked yes)
			(layer "F.Fab")
			(hide yes)
			(effects
				(font
					(size 1.016 1.016)
					(thickness 0.1524)
				)
			)
		)
		(duplicate_pad_numbers_are_jumpers no)
		(fp_line
			(start 2.1336 1.4224)
			(end 2.1336 -1.4224)
			(stroke
				(width 0.1524)
				(type default)
			)
			(layer "F.SilkS")
		)
		(fp_line
			(start 2.1336 -1.4224)
			(end -2.7432 -1.4224)
			(stroke
				(width 0.1524)
				(type default)
			)
			(layer "F.SilkS")
		)
		(fp_line
			(start -2.1844 -0.0508)
			(end -2.7178 0.508)
			(stroke
				(width 0.1524)
				(type default)
			)
			(layer "F.SilkS")
		)
		(fp_line
			(start -2.6289 3.4417)
			(end -2.6289 1.4732)
			(stroke
				(width 0.381)
				(type default)
			)
			(layer "F.SilkS")
		)
		(fp_line
			(start -2.7178 -0.508)
			(end -2.1844 -0.0508)
			(stroke
				(width 0.1524)
				(type default)
			)
			(layer "F.SilkS")
		)
		(fp_line
			(start -2.7432 1.4224)
			(end 2.1336 1.4224)
			(stroke
				(width 0.1524)
				(type default)
			)
			(layer "F.SilkS")
		)
		(fp_line
			(start -2.7432 1.4224)
			(end -2.6416 1.4224)
			(stroke
				(width 0.1524)
				(type default)
			)
			(layer "F.SilkS")
		)
		(fp_line
			(start -2.7432 -1.4224)
			(end -2.7432 1.4224)
			(stroke
				(width 0.1524)
				(type default)
			)
			(layer "F.SilkS")
		)
		(fp_poly
			(pts
				(xy -2.2098 -1.4224) (xy -2.2098 1.4224) (xy 2.2098 1.4224) (xy 2.2098 -1.4224)
			)
			(stroke
				(width 0)
				(type default)
			)
			(fill yes)
			(layer "F.SilkS")
		)
		(fp_rect
			(start -2.450084 2.999994)
			(end 2.450084 -2.999994)
			(stroke
				(width 0)
				(type default)
			)
			(fill no)
			(layer "F.CrtYd")
		)
		(fp_poly
			(pts
				(xy -2.8194 3.6322) (xy -2.8194 -3.6322) (xy 2.8194 -3.6322) (xy 2.8194 1.18364) (xy 2.450084 1.18364)
				(xy 2.450084 -2.999994) (xy -2.450084 -2.999994) (xy -2.450084 2.999994) (xy 2.450084 2.999994)
				(xy 2.450084 1.18618) (xy 2.8194 1.18618) (xy 2.8194 3.6322)
			)
			(stroke
				(width 0)
				(type default)
			)
			(fill no)
			(layer "F.CrtYd")
		)
		(fp_rect
			(start -2.8194 3.6322)
			(end 2.8194 -3.6322)
			(stroke
				(width 0)
				(type default)
			)
			(fill no)
			(layer "F.Fab")
		)
		(pad "1" smd rect
			(at -1.905 2.54 180)
			(size 0.635 1.651)
			(layers "F.Cu" "F.Mask" "F.Paste")
			(net "P5V_HDD13")
		)
		(pad "2" smd rect
			(at -0.635 2.54 180)
			(size 0.635 1.651)
			(layers "F.Cu" "F.Mask" "F.Paste")
			(net "P5V_HDD13")
		)
		(pad "3" smd rect
			(at 0.635 2.54 180)
			(size 0.635 1.651)
			(layers "F.Cu" "F.Mask" "F.Paste")
			(net "P5V_HDD13")
		)
		(pad "4" smd rect
			(at 1.905 2.54 180)
			(size 0.635 1.651)
			(layers "F.Cu" "F.Mask" "F.Paste")
			(net "SW_HDD_P13")
		)
		(pad "5" smd rect
			(at 1.905 -2.54 180)
			(size 0.635 1.651)
			(layers "F.Cu" "F.Mask" "F.Paste")
			(net "P5V_A_1")
		)
		(pad "6" smd rect
			(at 0.635 -2.54 180)
			(size 0.635 1.651)
			(layers "F.Cu" "F.Mask" "F.Paste")
			(net "P5V_A_1")
		)
		(pad "7" smd rect
			(at -0.635 -2.54 180)
			(size 0.635 1.651)
			(layers "F.Cu" "F.Mask" "F.Paste")
			(net "P5V_A_1")
		)
		(pad "8" smd rect
			(at -1.905 -2.54 180)
			(size 0.635 1.651)
			(layers "F.Cu" "F.Mask" "F.Paste")
			(net "P5V_A_1")
		)
	)
	(footprint ""
		(layer "F.Cu")
		(at 133.933438 -140.520674 -90)
		(property "Reference" "C94"
			(at 0 0 270)
			(layer "F.SilkS")
			(hide yes)
			(effects
				(font
					(size 1.27 1.27)
				)
			)
		)
		(property "Value" "SC1U16V3KX-5GP"
			(at 0 -2.8194 270)
			(unlocked yes)
			(layer "F.Fab")
			(hide yes)
			(effects
				(font
					(size 1.016 1.016)
					(thickness 0.1524)
				)
			)
		)
		(property "Device Type" "C603H36"
			(at 0 -4.3434 270)
			(unlocked yes)
			(layer "F.Fab")
			(hide yes)
			(effects
				(font
					(size 1.016 1.016)
					(thickness 0.1524)
				)
			)
		)
		(duplicate_pad_numbers_are_jumpers no)
		(fp_line
			(start 0.508 0)
			(end -0.508 0)
			(stroke
				(width 0.2032)
				(type default)
			)
			(layer "F.SilkS")
		)
		(fp_rect
			(start -0.5842 1.3335)
			(end 0.5842 -1.3335)
			(stroke
				(width 0)
				(type default)
			)
			(fill no)
			(layer "F.CrtYd")
		)
		(fp_rect
			(start -0.5842 1.3335)
			(end 0.5842 -1.3335)
			(stroke
				(width 0)
				(type default)
			)
			(fill no)
			(layer "F.Fab")
		)
		(pad "1" smd custom
			(at 0 -0.762 270)
			(size 0.2159 0.2159)
			(layers "F.Cu" "F.Mask" "F.Paste")
			(net "P3V3_A_BIAS")
			(options
				(clearance outline)
				(anchor circle)
			)
			(primitives
				(gr_poly
					(pts
						(arc
							(start -0.3302 -0.4318)
							(mid -0.402042 -0.402042)
							(end -0.4318 -0.3302)
						)
						(arc
							(start -0.4318 0.3302)
							(mid -0.402042 0.402042)
							(end -0.3302 0.4318)
						)
						(arc
							(start 0.3302 0.4318)
							(mid 0.402042 0.402042)
							(end 0.4318 0.3302)
						)
						(arc
							(start 0.4318 -0.3302)
							(mid 0.402042 -0.402042)
							(end 0.3302 -0.4318)
						)
					)
					(width 0)
					(fill yes)
				)
			)
		)
		(pad "2" smd custom
			(at 0 0.762 270)
			(size 0.2159 0.2159)
			(layers "F.Cu" "F.Mask" "F.Paste")
			(net "GND")
			(options
				(clearance outline)
				(anchor circle)
			)
			(primitives
				(gr_poly
					(pts
						(arc
							(start -0.3302 -0.4318)
							(mid -0.402042 -0.402042)
							(end -0.4318 -0.3302)
						)
						(arc
							(start -0.4318 0.3302)
							(mid -0.402042 0.402042)
							(end -0.3302 0.4318)
						)
						(arc
							(start 0.3302 0.4318)
							(mid 0.402042 0.402042)
							(end 0.4318 0.3302)
						)
						(arc
							(start 0.4318 -0.3302)
							(mid 0.402042 -0.402042)
							(end 0.3302 -0.4318)
						)
					)
					(width 0)
					(fill yes)
				)
			)
		)
	)
	(footprint ""
		(layer "F.Cu")
		(at 298.7294 -67.183 180)
		(property "Reference" "R631"
			(at 0 0 180)
			(layer "F.SilkS")
			(hide yes)
			(effects
				(font
					(size 1.27 1.27)
				)
			)
		)
		(property "Value" "4K7R2F-GP"
			(at 0.064008 -3.993896 180)
			(unlocked yes)
			(layer "F.Fab")
			(hide yes)
			(effects
				(font
					(size 1.016 1.016)
					(thickness 0.1524)
				)
			)
		)
		(property "Device Type" "R402H16"
			(at 0.064008 -5.517896 180)
			(unlocked yes)
			(layer "F.Fab")
			(hide yes)
			(effects
				(font
					(size 1.016 1.016)
					(thickness 0.1524)
				)
			)
		)
		(duplicate_pad_numbers_are_jumpers no)
		(fp_line
			(start 0.508 -0.9398)
			(end -0.508 -0.9398)
			(stroke
				(width 0.1524)
				(type default)
			)
			(layer "F.SilkS")
		)
		(fp_line
			(start -0.508 -0.9398)
			(end -0.508 0.9398)
			(stroke
				(width 0.1524)
				(type default)
			)
			(layer "F.SilkS")
		)
		(fp_rect
			(start -0.508 0.9398)
			(end 0.508 -0.9398)
			(stroke
				(width 0)
				(type default)
			)
			(fill no)
			(layer "F.CrtYd")
		)
		(fp_rect
			(start -0.508 0.9398)
			(end 0.508 -0.9398)
			(stroke
				(width 0)
				(type default)
			)
			(fill no)
			(layer "F.Fab")
		)
		(pad "1" smd custom
			(at 0 -0.4445 180)
			(size 0.1397 0.1397)
			(layers "F.Cu" "F.Mask" "F.Paste")
			(net "I2C_BMC_B_COMP_B_SDA")
			(options
				(clearance outline)
				(anchor circle)
			)
			(primitives
				(gr_poly
					(pts
						(arc
							(start -0.1778 -0.2794)
							(mid -0.249642 -0.249642)
							(end -0.2794 -0.1778)
						)
						(arc
							(start -0.2794 0.1778)
							(mid -0.249642 0.249642)
							(end -0.1778 0.2794)
						)
						(arc
							(start 0.1778 0.2794)
							(mid 0.249642 0.249642)
							(end 0.2794 0.1778)
						)
						(arc
							(start 0.2794 -0.1778)
							(mid 0.249642 -0.249642)
							(end 0.1778 -0.2794)
						)
					)
					(width 0)
					(fill yes)
				)
			)
		)
		(pad "2" smd custom
			(at 0 0.4445 180)
			(size 0.1397 0.1397)
			(layers "F.Cu" "F.Mask" "F.Paste")
			(net "P3V3_STBY_B")
			(options
				(clearance outline)
				(anchor circle)
			)
			(primitives
				(gr_poly
					(pts
						(arc
							(start -0.1778 -0.2794)
							(mid -0.249642 -0.249642)
							(end -0.2794 -0.1778)
						)
						(arc
							(start -0.2794 0.1778)
							(mid -0.249642 0.249642)
							(end -0.1778 0.2794)
						)
						(arc
							(start 0.1778 0.2794)
							(mid 0.249642 0.249642)
							(end 0.2794 0.1778)
						)
						(arc
							(start 0.2794 -0.1778)
							(mid 0.249642 -0.249642)
							(end 0.1778 -0.2794)
						)
					)
					(width 0)
					(fill yes)
				)
			)
		)
	)
	(footprint ""
		(layer "F.Cu")
		(at 46.773846 -47.183294 180)
		(property "Reference" "R721"
			(at 0 0 180)
			(layer "F.SilkS")
			(hide yes)
			(effects
				(font
					(size 1.27 1.27)
				)
			)
		)
		(property "Value" "200KR2F-L-GP"
			(at 0.064008 -3.993896 180)
			(unlocked yes)
			(layer "F.Fab")
			(hide yes)
			(effects
				(font
					(size 1.016 1.016)
					(thickness 0.1524)
				)
			)
		)
		(property "Device Type" "R402H16"
			(at 0.064008 -5.517896 180)
			(unlocked yes)
			(layer "F.Fab")
			(hide yes)
			(effects
				(font
					(size 1.016 1.016)
					(thickness 0.1524)
				)
			)
		)
		(duplicate_pad_numbers_are_jumpers no)
		(fp_line
			(start 0.508 -0.9398)
			(end -0.508 -0.9398)
			(stroke
				(width 0.1524)
				(type default)
			)
			(layer "F.SilkS")
		)
		(fp_line
			(start -0.508 -0.9398)
			(end -0.508 0.9398)
			(stroke
				(width 0.1524)
				(type default)
			)
			(layer "F.SilkS")
		)
		(fp_rect
			(start -0.508 0.9398)
			(end 0.508 -0.9398)
			(stroke
				(width 0)
				(type default)
			)
			(fill no)
			(layer "F.CrtYd")
		)
		(fp_rect
			(start -0.508 0.9398)
			(end 0.508 -0.9398)
			(stroke
				(width 0)
				(type default)
			)
			(fill no)
			(layer "F.Fab")
		)
		(pad "1" smd custom
			(at 0 -0.4445 180)
			(size 0.1397 0.1397)
			(layers "F.Cu" "F.Mask" "F.Paste")
			(net "SW_HDD_R25")
			(options
				(clearance outline)
				(anchor circle)
			)
			(primitives
				(gr_poly
					(pts
						(arc
							(start -0.1778 -0.2794)
							(mid -0.249642 -0.249642)
							(end -0.2794 -0.1778)
						)
						(arc
							(start -0.2794 0.1778)
							(mid -0.249642 0.249642)
							(end -0.1778 0.2794)
						)
						(arc
							(start 0.1778 0.2794)
							(mid 0.249642 0.249642)
							(end 0.2794 0.1778)
						)
						(arc
							(start 0.2794 -0.1778)
							(mid 0.249642 -0.249642)
							(end 0.1778 -0.2794)
						)
					)
					(width 0)
					(fill yes)
				)
			)
		)
		(pad "2" smd custom
			(at 0 0.4445 180)
			(size 0.1397 0.1397)
			(layers "F.Cu" "F.Mask" "F.Paste")
			(net "SW_HDD_N25")
			(options
				(clearance outline)
				(anchor circle)
			)
			(primitives
				(gr_poly
					(pts
						(arc
							(start -0.1778 -0.2794)
							(mid -0.249642 -0.249642)
							(end -0.2794 -0.1778)
						)
						(arc
							(start -0.2794 0.1778)
							(mid -0.249642 0.249642)
							(end -0.1778 0.2794)
						)
						(arc
							(start 0.1778 0.2794)
							(mid 0.249642 0.249642)
							(end 0.2794 0.1778)
						)
						(arc
							(start 0.2794 -0.1778)
							(mid 0.249642 -0.249642)
							(end 0.1778 -0.2794)
						)
					)
					(width 0)
					(fill yes)
				)
			)
		)
	)
	(footprint ""
		(layer "F.Cu")
		(at 363.909102 -295.826942 180)
		(property "Reference" "C132"
			(at 0 0 180)
			(layer "F.SilkS")
			(hide yes)
			(effects
				(font
					(size 1.27 1.27)
				)
			)
		)
		(property "Value" "SC10U16V6KX-2GP"
			(at -0.0762 -5.1308 180)
			(unlocked yes)
			(layer "F.Fab")
			(hide yes)
			(effects
				(font
					(size 1.016 1.016)
					(thickness 0.1524)
				)
			)
		)
		(property "Device Type" "C1206H71"
			(at -0.127 -6.6548 180)
			(unlocked yes)
			(layer "F.Fab")
			(hide yes)
			(effects
				(font
					(size 1.016 1.016)
					(thickness 0.1524)
				)
			)
		)
		(duplicate_pad_numbers_are_jumpers no)
		(fp_line
			(start 1.016 2.2352)
			(end -1.016 2.2352)
			(stroke
				(width 0.1524)
				(type default)
			)
			(layer "F.SilkS")
		)
		(fp_line
			(start 1.016 0.8382)
			(end 1.016 2.2352)
			(stroke
				(width 0.1524)
				(type default)
			)
			(layer "F.SilkS")
		)
		(fp_line
			(start 1.016 -2.2352)
			(end 1.016 -0.8382)
			(stroke
				(width 0.1524)
				(type default)
			)
			(layer "F.SilkS")
		)
		(fp_line
			(start -1.016 2.2352)
			(end -1.016 0.8382)
			(stroke
				(width 0.1524)
				(type default)
			)
			(layer "F.SilkS")
		)
		(fp_line
			(start -1.016 -0.8382)
			(end -1.016 -2.2352)
			(stroke
				(width 0.1524)
				(type default)
			)
			(layer "F.SilkS")
		)
		(fp_line
			(start -1.016 -2.2352)
			(end 1.016 -2.2352)
			(stroke
				(width 0.1524)
				(type default)
			)
			(layer "F.SilkS")
		)
		(fp_rect
			(start -1.0922 2.3114)
			(end 1.0922 -2.3114)
			(stroke
				(width 0)
				(type default)
			)
			(fill no)
			(layer "F.CrtYd")
		)
		(fp_poly
			(pts
				(xy 1.0922 -2.3114) (xy 1.0922 2.3114) (xy -1.0922 2.3114) (xy -1.0922 -2.3114)
			)
			(stroke
				(width 0)
				(type default)
			)
			(fill no)
			(layer "F.Fab")
		)
		(pad "1" smd rect
			(at 0 -1.397 180)
			(size 1.651 1.27)
			(layers "F.Cu" "F.Mask" "F.Paste")
			(net "P5V_HDD7")
		)
		(pad "2" smd rect
			(at 0 1.397 180)
			(size 1.651 1.27)
			(layers "F.Cu" "F.Mask" "F.Paste")
			(net "GND")
		)
	)
)
